# T6G (Grand Teton) — schematic netlist excerpt (pin names and nets, part order shuffled) for the footprints in the layout excerpt that follows; sources: Cadence DE-HDL packaged netlist, KiCad conversion of 04192023_DAF0TMB3IC0_F0TG_MB_C_brd_V02_OCP.brd

PC852  Q_CAP  330PF 50V 10% X7R  pkg 0402  page 270 : A = P1V2_AUX_FB ; B = P1V2_AUX
PR6628  Q_RES  8.87K 1% EMPTY  pkg 0402LF  page 365 : A = P0V9_RETIMER_CPU1_LSET2 ; B = GND

(kicad_pcb
	(version 20260206)
	(generator "pcbnew")
	(generator_version "10.0")
	(general
		(thickness 1.6)
		(legacy_teardrops no)
	)
	(paper "A4")
	(title_block
		(title "04192023_DAF0TMB3IC0_F0TG_MB_C_brd_V02_OCP.brd")
		(comment 1 "Grand Teton / footprints 3268-3269 of 8354")
	)
	(layers
		(0 "F.Cu" signal "TOP")
		(4 "In1.Cu" signal "GND")
		(6 "In2.Cu" signal "IN1")
		(8 "In3.Cu" signal "GND1")
		(10 "In4.Cu" signal "IN2")
		(12 "In5.Cu" signal "GND2")
		(14 "In6.Cu" signal "IN3")
		(16 "In7.Cu" signal "GND3")
		(18 "In8.Cu" signal "VCC")
		(20 "In9.Cu" signal "VCC1")
		(22 "In10.Cu" signal "GND4")
		(24 "In11.Cu" signal "IN4")
		(26 "In12.Cu" signal "GND5")
		(28 "In13.Cu" signal "IN5")
		(30 "In14.Cu" signal "GND6")
		(32 "In15.Cu" signal "IN6")
		(34 "In16.Cu" signal "GND7")
		(2 "B.Cu" signal "BOTTOM")
		(9 "F.Adhes" user "F.Adhesive")
		(11 "B.Adhes" user "B.Adhesive")
		(13 "F.Paste" user "Package Geometry/Pastemask Top")
		(15 "B.Paste" user "Package Geometry/Pastemask Bottom")
		(5 "F.SilkS" user "Ref Des/Silkscreen Top")
		(7 "B.SilkS" user "Ref Des/Silkscreen Bottom")
		(1 "F.Mask" user "Board Geometry/Soldermask Top")
		(3 "B.Mask" user "Board Geometry/Soldermask Bottom")
		(17 "Dwgs.User" user "User.Drawings")
		(19 "Cmts.User" user "User.Comments")
		(21 "Eco1.User" user "User.Eco1")
		(23 "Eco2.User" user "User.Eco2")
		(25 "Edge.Cuts" user "Board Geometry/Outline")
		(27 "Margin" user)
		(31 "F.CrtYd" user "Package Geometry/Place Bound Top")
		(29 "B.CrtYd" user "Package Geometry/Place Bound Bottom")
		(35 "F.Fab" user "Ref Des/Assembly Top")
		(33 "B.Fab" user "Ref Des/Assembly Bottom")
	)
	(footprint ""
		(layer "F.Cu")
		(at 120.631712 -72.323452)
		(property "Reference" "PC852"
			(at 0 0 0)
			(layer "F.SilkS")
			(hide yes)
			(effects
				(font
					(size 1.27 1.27)
				)
			)
		)
		(property "Value" ""
			(at 0 0 0)
			(layer "F.Fab")
			(effects
				(font
					(size 1.27 1.27)
				)
			)
		)
		(duplicate_pad_numbers_are_jumpers no)
		(fp_line
			(start -0.7874 -0.4064)
			(end 0.7874 -0.4064)
			(stroke
				(width 0.1524)
				(type default)
			)
			(layer "F.SilkS")
		)
		(fp_line
			(start -0.7874 0.4064)
			(end -0.7874 -0.4064)
			(stroke
				(width 0.1524)
				(type default)
			)
			(layer "F.SilkS")
		)
		(fp_line
			(start 0.7874 -0.4064)
			(end 0.7874 0.4064)
			(stroke
				(width 0.1524)
				(type default)
			)
			(layer "F.SilkS")
		)
		(fp_line
			(start 0.7874 0.4064)
			(end -0.7874 0.4064)
			(stroke
				(width 0.1524)
				(type default)
			)
			(layer "F.SilkS")
		)
		(fp_line
			(start -0.67945 -0.305054)
			(end -0.12065 -0.305054)
			(stroke
				(width 0.1)
				(type default)
			)
			(layer "F.Fab")
		)
		(fp_line
			(start -0.67945 0.3048)
			(end -0.67945 -0.305054)
			(stroke
				(width 0.1)
				(type default)
			)
			(layer "F.Fab")
		)
		(fp_line
			(start -0.12065 -0.305054)
			(end -0.12065 -0.2794)
			(stroke
				(width 0.1)
				(type default)
			)
			(layer "F.Fab")
		)
		(fp_line
			(start -0.12065 -0.2794)
			(end 0.12065 -0.2794)
			(stroke
				(width 0.1)
				(type default)
			)
			(layer "F.Fab")
		)
		(fp_line
			(start -0.12065 0.2794)
			(end -0.12065 0.3048)
			(stroke
				(width 0.1)
				(type default)
			)
			(layer "F.Fab")
		)
		(fp_line
			(start -0.12065 0.3048)
			(end -0.67945 0.3048)
			(stroke
				(width 0.1)
				(type default)
			)
			(layer "F.Fab")
		)
		(fp_line
			(start 0.120396 0.2794)
			(end -0.12065 0.2794)
			(stroke
				(width 0.1)
				(type default)
			)
			(layer "F.Fab")
		)
		(fp_line
			(start 0.120396 0.3048)
			(end 0.120396 0.2794)
			(stroke
				(width 0.1)
				(type default)
			)
			(layer "F.Fab")
		)
		(fp_line
			(start 0.12065 -0.3048)
			(end 0.67945 -0.3048)
			(stroke
				(width 0.1)
				(type default)
			)
			(layer "F.Fab")
		)
		(fp_line
			(start 0.12065 -0.2794)
			(end 0.12065 -0.3048)
			(stroke
				(width 0.1)
				(type default)
			)
			(layer "F.Fab")
		)
		(fp_line
			(start 0.67945 -0.3048)
			(end 0.67945 0.3048)
			(stroke
				(width 0.1)
				(type default)
			)
			(layer "F.Fab")
		)
		(fp_line
			(start 0.67945 0.3048)
			(end 0.120396 0.3048)
			(stroke
				(width 0.1)
				(type default)
			)
			(layer "F.Fab")
		)
		(pad "1" smd circle
			(at -0.40005 0)
			(size 0 0)
			(layers "F.Cu" "F.Mask" "F.Paste")
			(net "P1V2_AUX_FB")
		)
		(pad "2" smd circle
			(at 0.40005 0)
			(size 0 0)
			(layers "F.Cu" "F.Mask" "F.Paste")
			(net "P1V2_AUX")
		)
	)
	(footprint ""
		(layer "F.Cu")
		(at 24.640794 -394.410184)
		(property "Reference" "PR6628"
			(at 0 0 0)
			(layer "F.SilkS")
			(hide yes)
			(effects
				(font
					(size 1.27 1.27)
				)
			)
		)
		(property "Value" ""
			(at 0 0 0)
			(layer "F.Fab")
			(effects
				(font
					(size 1.27 1.27)
				)
			)
		)
		(duplicate_pad_numbers_are_jumpers no)
		(fp_line
			(start -0.7874 -0.4064)
			(end 0.7874 -0.4064)
			(stroke
				(width 0.1524)
				(type default)
			)
			(layer "F.SilkS")
		)
		(fp_line
			(start -0.7874 0.4064)
			(end -0.7874 -0.4064)
			(stroke
				(width 0.1524)
				(type default)
			)
			(layer "F.SilkS")
		)
		(fp_line
			(start 0.7874 -0.4064)
			(end 0.7874 0.4064)
			(stroke
				(width 0.1524)
				(type default)
			)
			(layer "F.SilkS")
		)
		(fp_line
			(start 0.7874 0.4064)
			(end -0.7874 0.4064)
			(stroke
				(width 0.1524)
				(type default)
			)
			(layer "F.SilkS")
		)
		(fp_line
			(start -0.67945 -0.305054)
			(end -0.12065 -0.305054)
			(stroke
				(width 0.1)
				(type default)
			)
			(layer "F.Fab")
		)
		(fp_line
			(start -0.67945 0.3048)
			(end -0.67945 -0.305054)
			(stroke
				(width 0.1)
				(type default)
			)
			(layer "F.Fab")
		)
		(fp_line
			(start -0.12065 -0.305054)
			(end -0.12065 -0.2794)
			(stroke
				(width 0.1)
				(type default)
			)
			(layer "F.Fab")
		)
		(fp_line
			(start -0.12065 -0.2794)
			(end 0.12065 -0.2794)
			(stroke
				(width 0.1)
				(type default)
			)
			(layer "F.Fab")
		)
		(fp_line
			(start -0.12065 0.2794)
			(end -0.12065 0.3048)
			(stroke
				(width 0.1)
				(type default)
			)
			(layer "F.Fab")
		)
		(fp_line
			(start -0.12065 0.3048)
			(end -0.67945 0.3048)
			(stroke
				(width 0.1)
				(type default)
			)
			(layer "F.Fab")
		)
		(fp_line
			(start 0.120396 0.2794)
			(end -0.12065 0.2794)
			(stroke
				(width 0.1)
				(type default)
			)
			(layer "F.Fab")
		)
		(fp_line
			(start 0.120396 0.3048)
			(end 0.120396 0.2794)
			(stroke
				(width 0.1)
				(type default)
			)
			(layer "F.Fab")
		)
		(fp_line
			(start 0.12065 -0.3048)
			(end 0.67945 -0.3048)
			(stroke
				(width 0.1)
				(type default)
			)
			(layer "F.Fab")
		)
		(fp_line
			(start 0.12065 -0.2794)
			(end 0.12065 -0.3048)
			(stroke
				(width 0.1)
				(type default)
			)
			(layer "F.Fab")
		)
		(fp_line
			(start 0.67945 -0.3048)
			(end 0.67945 0.3048)
			(stroke
				(width 0.1)
				(type default)
			)
			(layer "F.Fab")
		)
		(fp_line
			(start 0.67945 0.3048)
			(end 0.120396 0.3048)
			(stroke
				(width 0.1)
				(type default)
			)
			(layer "F.Fab")
		)
		(pad "1" smd circle
			(at -0.40005 0)
			(size 0 0)
			(layers "F.Cu" "F.Mask" "F.Paste")
			(net "P0V9_RETIMER_CPU1_LSET2")
		)
		(pad "2" smd circle
			(at 0.40005 0)
			(size 0 0)
			(layers "F.Cu" "F.Mask" "F.Paste")
			(net "GND")
		)
	)
)
